(kicad_pcb
	(version 20241229)
	(generator "pcbnew")
	(generator_version "9.0")
	(general
		(thickness 1.6642)
		(legacy_teardrops no)
	)
	(paper "A3")
	(title_block
		(title "PolarFire SoM")
		(date "2025-07-22")
		(rev "1.1.4")
		(company "Antmicro Ltd")
		(comment 1 "www.antmicro.com")
		(comment 9 "footprints 178-181 of 470")
	)
	(layers
		(0 "F.Cu" mixed)
		(4 "In1.Cu" power)
		(6 "In2.Cu" signal)
		(8 "In3.Cu" power)
		(10 "In4.Cu" signal)
		(12 "In5.Cu" power)
		(14 "In6.Cu" power)
		(16 "In7.Cu" signal)
		(18 "In8.Cu" power)
		(20 "In9.Cu" signal)
		(22 "In10.Cu" power)
		(24 "In11.Cu" signal)
		(26 "In12.Cu" signal)
		(2 "B.Cu" mixed)
		(9 "F.Adhes" user "F.Adhesive")
		(11 "B.Adhes" user "B.Adhesive")
		(13 "F.Paste" user)
		(15 "B.Paste" user)
		(5 "F.SilkS" user "F.Silkscreen")
		(7 "B.SilkS" user "B.Silkscreen")
		(1 "F.Mask" user)
		(3 "B.Mask" user)
		(17 "Dwgs.User" user "User.Drawings")
		(19 "Cmts.User" user "User.Comments")
		(21 "Eco1.User" user "User.Eco1")
		(23 "Eco2.User" user "User.Eco2")
		(25 "Edge.Cuts" user)
		(27 "Margin" user)
		(31 "F.CrtYd" user "F.Courtyard")
		(29 "B.CrtYd" user "B.Courtyard")
		(35 "F.Fab" user)
		(33 "B.Fab" user)
	)
	(footprint "antmicro-footprints:C_0402_1005Metric"
		(layer "B.Cu")
		(at 205.25 147.41 180)
		(descr "Capacitor SMD 0402")
		(tags "capacitor SMD 0402")
		(property "Reference" "C210"
			(at -1.8 8.64 0)
			(layer "B.SilkS")
			(effects
				(font
					(size 0.7 0.7)
					(thickness 0.15)
				)
				(justify left bottom mirror)
			)
		)
		(property "Value" "C_100n_0402"
			(at -1.022927 -2.155213 0)
			(layer "B.Fab")
			(hide yes)
			(effects
				(font
					(size 0.7 0.7)
					(thickness 0.15)
				)
				(justify left bottom mirror)
			)
		)
		(property "Datasheet" "https://www.murata.com/products/productdetail?partno=GRM155R61H104KE14%23"
			(at 0 0 180)
			(layer "F.Fab")
			(hide yes)
			(effects
				(font
					(size 1.27 1.27)
					(thickness 0.15)
				)
			)
		)
		(property "Description" "SMD Multilayer Ceramic Capacitor, 0.1 µF, 50 V, 0402 [1005 Metric], ± 10%, X5R, GRM Series"
			(at 0 0 180)
			(layer "F.Fab")
			(hide yes)
			(effects
				(font
					(size 1.27 1.27)
					(thickness 0.15)
				)
			)
		)
		(property "Author" "Antmicro"
			(at 410.5 294.82 0)
			(layer "B.Fab")
			(hide yes)
			(effects
				(font
					(size 1 1)
					(thickness 0.15)
				)
				(justify mirror)
			)
		)
		(property "Dielectric" "X5R"
			(at 410.5 294.82 0)
			(layer "B.Fab")
			(hide yes)
			(effects
				(font
					(size 1 1)
					(thickness 0.15)
				)
				(justify mirror)
			)
		)
		(property "License" "Apache-2.0"
			(at 410.5 294.82 0)
			(layer "B.Fab")
			(hide yes)
			(effects
				(font
					(size 1 1)
					(thickness 0.15)
				)
				(justify mirror)
			)
		)
		(property "MPN" "GRM155R61H104KE14D"
			(at 410.5 294.82 0)
			(layer "B.Fab")
			(hide yes)
			(effects
				(font
					(size 1 1)
					(thickness 0.15)
				)
				(justify mirror)
			)
		)
		(property "Manufacturer" "Murata"
			(at 410.5 294.82 0)
			(layer "B.Fab")
			(hide yes)
			(effects
				(font
					(size 1 1)
					(thickness 0.15)
				)
				(justify mirror)
			)
		)
		(property "Public" ""
			(at 410.5 294.82 0)
			(layer "B.Fab")
			(hide yes)
			(effects
				(font
					(size 1 1)
					(thickness 0.15)
				)
				(justify mirror)
			)
		)
		(property "Val" "100n"
			(at 410.5 294.82 0)
			(layer "B.Fab")
			(hide yes)
			(effects
				(font
					(size 1 1)
					(thickness 0.15)
				)
				(justify mirror)
			)
		)
		(property "Voltage" "50V"
			(at 410.5 294.82 0)
			(layer "B.Fab")
			(hide yes)
			(effects
				(font
					(size 1 1)
					(thickness 0.15)
				)
				(justify mirror)
			)
		)
		(sheetname "/MIPI CrossLink/")
		(sheetfile "crosslink.kicad_sch")
		(attr smd)
		(fp_rect
			(start -0.925 0.47)
			(end 0.925 -0.47)
			(stroke
				(width 0.05)
				(type default)
			)
			(fill no)
			(layer "B.CrtYd")
		)
		(fp_line
			(start 0.504 0.25)
			(end 0.504 -0.248)
			(stroke
				(width 0.15)
				(type solid)
			)
			(layer "B.Fab")
		)
		(fp_line
			(start 0.504 -0.248)
			(end -0.494 -0.248)
			(stroke
				(width 0.15)
				(type solid)
			)
			(layer "B.Fab")
		)
		(fp_line
			(start -0.494 0.25)
			(end 0.504 0.25)
			(stroke
				(width 0.15)
				(type solid)
			)
			(layer "B.Fab")
		)
		(fp_line
			(start -0.494 -0.248)
			(end -0.494 0.25)
			(stroke
				(width 0.15)
				(type solid)
			)
			(layer "B.Fab")
		)
		(fp_text user "${REFERENCE}"
			(at -0.939 -4.599 0)
			(layer "B.Fab")
			(effects
				(font
					(size 0.7 0.7)
					(thickness 0.15)
				)
				(justify left bottom mirror)
			)
		)
		(fp_text user "License: Apache-2.0"
			(at -0.939 -5.799 0)
			(layer "B.Fab")
			(effects
				(font
					(size 0.7 0.7)
					(thickness 0.15)
				)
				(justify left bottom mirror)
			)
		)
		(fp_text user "Author: Antmicro"
			(at -0.939 -3.399 0)
			(layer "B.Fab")
			(effects
				(font
					(size 0.7 0.7)
					(thickness 0.15)
				)
				(justify left bottom mirror)
			)
		)
		(pad "1" smd roundrect
			(at -0.48 0 180)
			(size 0.59 0.64)
			(layers "B.Cu" "B.Mask" "B.Paste")
			(roundrect_rratio 0.25)
			(net 417 "GND")
			(pintype "passive")
		)
		(pad "2" smd roundrect
			(at 0.48 0 180)
			(size 0.59 0.64)
			(layers "B.Cu" "B.Mask" "B.Paste")
			(roundrect_rratio 0.25)
			(net 176 "/MIPI CrossLink/CL_VCC")
			(pintype "passive")
		)
	)
	(footprint "antmicro-footprints:C_0402_1005Metric"
		(layer "B.Cu")
		(at 183.25 134.1 90)
		(descr "Capacitor SMD 0402")
		(tags "capacitor SMD 0402")
		(property "Reference" "C158"
			(at -1.21 -0.56 90)
			(layer "B.SilkS")
			(effects
				(font
					(size 0.7 0.7)
					(thickness 0.15)
				)
				(justify right bottom mirror)
			)
		)
		(property "Value" "C_1u_0402"
			(at -1.022927 -2.155213 90)
			(layer "B.Fab")
			(hide yes)
			(effects
				(font
					(size 0.7 0.7)
					(thickness 0.15)
				)
				(justify right bottom mirror)
			)
		)
		(property "Datasheet" "https://product.tdk.com/en/search/capacitor/ceramic/mlcc/info?part_no=C1005X6S1A105K050BC"
			(at 0 0 90)
			(layer "F.Fab")
			(hide yes)
			(effects
				(font
					(size 1.27 1.27)
					(thickness 0.15)
				)
			)
		)
		(property "Description" "SMD Multilayer Ceramic Capacitor, 1 µF, 10 V, 0402 [1005 Metric], ± 10%, X6S, C"
			(at 0 0 90)
			(layer "F.Fab")
			(hide yes)
			(effects
				(font
					(size 1.27 1.27)
					(thickness 0.15)
				)
			)
		)
		(property "Author" "Antmicro"
			(at 317.35 -49.15 0)
			(layer "B.Fab")
			(hide yes)
			(effects
				(font
					(size 1 1)
					(thickness 0.15)
				)
				(justify mirror)
			)
		)
		(property "Dielectric" "X5R"
			(at 317.35 -49.15 0)
			(layer "B.Fab")
			(hide yes)
			(effects
				(font
					(size 1 1)
					(thickness 0.15)
				)
				(justify mirror)
			)
		)
		(property "License" "Apache-2.0"
			(at 317.35 -49.15 0)
			(layer "B.Fab")
			(hide yes)
			(effects
				(font
					(size 1 1)
					(thickness 0.15)
				)
				(justify mirror)
			)
		)
		(property "MPN" "C1005X6S1A105K050BC"
			(at 317.35 -49.15 0)
			(layer "B.Fab")
			(hide yes)
			(effects
				(font
					(size 1 1)
					(thickness 0.15)
				)
				(justify mirror)
			)
		)
		(property "Manufacturer" "TDK"
			(at 317.35 -49.15 0)
			(layer "B.Fab")
			(hide yes)
			(effects
				(font
					(size 1 1)
					(thickness 0.15)
				)
				(justify mirror)
			)
		)
		(property "Public" ""
			(at 317.35 -49.15 0)
			(layer "B.Fab")
			(hide yes)
			(effects
				(font
					(size 1 1)
					(thickness 0.15)
				)
				(justify mirror)
			)
		)
		(property "Val" "1u"
			(at 317.35 -49.15 0)
			(layer "B.Fab")
			(hide yes)
			(effects
				(font
					(size 1 1)
					(thickness 0.15)
				)
				(justify mirror)
			)
		)
		(property "Voltage" "16V"
			(at 317.35 -49.15 0)
			(layer "B.Fab")
			(hide yes)
			(effects
				(font
					(size 1 1)
					(thickness 0.15)
				)
				(justify mirror)
			)
		)
		(sheetname "/LPDDR4/")
		(sheetfile "lpddr.kicad_sch")
		(attr smd)
		(fp_rect
			(start -0.925 0.47)
			(end 0.925 -0.47)
			(stroke
				(width 0.05)
				(type default)
			)
			(fill no)
			(layer "B.CrtYd")
		)
		(fp_line
			(start 0.504 -0.248)
			(end -0.494 -0.248)
			(stroke
				(width 0.15)
				(type solid)
			)
			(layer "B.Fab")
		)
		(fp_line
			(start -0.494 -0.248)
			(end -0.494 0.25)
			(stroke
				(width 0.15)
				(type solid)
			)
			(layer "B.Fab")
		)
		(fp_line
			(start 0.504 0.25)
			(end 0.504 -0.248)
			(stroke
				(width 0.15)
				(type solid)
			)
			(layer "B.Fab")
		)
		(fp_line
			(start -0.494 0.25)
			(end 0.504 0.25)
			(stroke
				(width 0.15)
				(type solid)
			)
			(layer "B.Fab")
		)
		(fp_text user "License: Apache-2.0"
			(at -0.939 -5.799 270)
			(layer "B.Fab")
			(effects
				(font
					(size 0.7 0.7)
					(thickness 0.15)
				)
				(justify left bottom mirror)
			)
		)
		(fp_text user "${REFERENCE}"
			(at -0.939 -4.599 270)
			(layer "B.Fab")
			(effects
				(font
					(size 0.7 0.7)
					(thickness 0.15)
				)
				(justify left bottom mirror)
			)
		)
		(fp_text user "Author: Antmicro"
			(at -0.939 -3.399 270)
			(layer "B.Fab")
			(effects
				(font
					(size 0.7 0.7)
					(thickness 0.15)
				)
				(justify left bottom mirror)
			)
		)
		(pad "1" smd roundrect
			(at -0.48 0 90)
			(size 0.59 0.64)
			(layers "B.Cu" "B.Mask" "B.Paste")
			(roundrect_rratio 0.25)
			(net 417 "GND")
			(pintype "passive")
		)
		(pad "2" smd roundrect
			(at 0.48 0 90)
			(size 0.59 0.64)
			(layers "B.Cu" "B.Mask" "B.Paste")
			(roundrect_rratio 0.25)
			(net 2 "+1V1")
			(pintype "passive")
		)
	)
	(footprint "antmicro-footprints:SOT-583"
		(layer "B.Cu")
		(at 222.175 138.875 -90)
		(property "Reference" "U9"
			(at -1.225 1.35 90)
			(layer "B.SilkS")
			(effects
				(font
					(size 0.7 0.7)
					(thickness 0.15)
				)
				(justify left bottom mirror)
			)
		)
		(property "Value" "TPS2117DRLR"
			(at 0 -2.3 90)
			(layer "B.Fab")
			(hide yes)
			(effects
				(font
					(size 0.7 0.7)
					(thickness 0.15)
				)
				(justify left bottom mirror)
			)
		)
		(property "Datasheet" "https://www.ti.com/lit/ds/symlink/tps2117.pdf"
			(at 0 0 270)
			(layer "F.Fab")
			(hide yes)
			(effects
				(font
					(size 1.27 1.27)
					(thickness 0.15)
				)
			)
		)
		(property "Description" "TPS2117 1.6-V to 5.5-V, 4-A Low IQ Power Mux With Manual and Priority Switchover"
			(at 0 0 270)
			(layer "F.Fab")
			(hide yes)
			(effects
				(font
					(size 1.27 1.27)
					(thickness 0.15)
				)
			)
		)
		(property "Author" "Antmicro"
			(at 83.3 361.05 0)
			(layer "B.Fab")
			(hide yes)
			(effects
				(font
					(size 1 1)
					(thickness 0.15)
				)
				(justify mirror)
			)
		)
		(property "License" "Apache-2.0"
			(at 83.3 361.05 0)
			(layer "B.Fab")
			(hide yes)
			(effects
				(font
					(size 1 1)
					(thickness 0.15)
				)
				(justify mirror)
			)
		)
		(property "MPN" "TPS2117DRLR"
			(at 83.3 361.05 0)
			(layer "B.Fab")
			(hide yes)
			(effects
				(font
					(size 1 1)
					(thickness 0.15)
				)
				(justify mirror)
			)
		)
		(property "Manufacturer" "Texas Instruments"
			(at 83.3 361.05 0)
			(layer "B.Fab")
			(hide yes)
			(effects
				(font
					(size 1 1)
					(thickness 0.15)
				)
				(justify mirror)
			)
		)
		(property ki_fp_filters "DRL0008A-MFG")
		(sheetname "/Memory/")
		(sheetfile "memory.kicad_sch")
		(attr smd)
		(fp_line
			(start -0.65 1.15)
			(end 0.65 1.15)
			(stroke
				(width 0.15)
				(type solid)
			)
			(layer "B.SilkS")
		)
		(fp_line
			(start -0.651 -1.15)
			(end 0.651 -1.15)
			(stroke
				(width 0.15)
				(type solid)
			)
			(layer "B.SilkS")
		)
		(fp_circle
			(center -0.9 1.1)
			(end -0.85 1.05)
			(stroke
				(width 0.15)
				(type solid)
			)
			(fill yes)
			(layer "B.SilkS")
		)
		(fp_rect
			(start -1.15 1.3)
			(end 1.15 -1.3)
			(stroke
				(width 0.05)
				(type solid)
			)
			(fill no)
			(layer "B.CrtYd")
		)
		(fp_line
			(start -0.651 1.1005)
			(end 0.651 1.1005)
			(stroke
				(width 0.15)
				(type solid)
			)
			(layer "B.Fab")
		)
		(fp_line
			(start -0.651 -1.1005)
			(end -0.651 1.1005)
			(stroke
				(width 0.15)
				(type solid)
			)
			(layer "B.Fab")
		)
		(fp_line
			(start -0.651 -1.1005)
			(end 0.651 -1.1005)
			(stroke
				(width 0.15)
				(type solid)
			)
			(layer "B.Fab")
		)
		(fp_line
			(start 0.651 -1.1005)
			(end 0.651 1.1005)
			(stroke
				(width 0.15)
				(type solid)
			)
			(layer "B.Fab")
		)
		(fp_text user "Author: Antmicro"
			(at -0.06 -5.025 90)
			(layer "B.Fab")
			(effects
				(font
					(size 0.7 0.7)
					(thickness 0.15)
				)
				(justify left bottom mirror)
			)
		)
		(fp_text user "${REFERENCE}"
			(at -0.06 -4.025 90)
			(layer "B.Fab")
			(effects
				(font
					(size 0.7 0.7)
					(thickness 0.15)
				)
				(justify left bottom mirror)
			)
		)
		(fp_text user "License: Apache-2.0"
			(at -0.06 -6.025 90)
			(layer "B.Fab")
			(effects
				(font
					(size 0.7 0.7)
					(thickness 0.15)
				)
				(justify left bottom mirror)
			)
		)
		(pad "1" smd roundrect
			(at -0.739 0.7495 270)
			(size 0.670001 0.299999)
			(layers "B.Cu" "B.Mask" "B.Paste")
			(roundrect_rratio 0.25)
			(net 417 "GND")
			(pinfunction "GND")
			(pintype "power_in")
		)
		(pad "2" smd roundrect
			(at -0.739 0.2505 270)
			(size 0.670001 0.299999)
			(layers "B.Cu" "B.Mask" "B.Paste")
			(roundrect_rratio 0.25)
			(net 516 "Net-(R50-Pad1)")
			(pinfunction "VOUT")
			(pintype "power_out")
		)
		(pad "3" smd roundrect
			(at -0.739 -0.2495 270)
			(size 0.670001 0.299999)
			(layers "B.Cu" "B.Mask" "B.Paste")
			(roundrect_rratio 0.25)
			(net 48 "+1V8")
			(pinfunction "VIN1")
			(pintype "power_in")
		)
		(pad "4" smd roundrect
			(at -0.739 -0.7495 270)
			(size 0.670001 0.299999)
			(layers "B.Cu" "B.Mask" "B.Paste")
			(roundrect_rratio 0.25)
			(net 246 "SD_VDD_OVERRIDE")
			(pinfunction "PR1")
			(pintype "input")
		)
		(pad "5" smd roundrect
			(at 0.74 -0.7495 270)
			(size 0.670001 0.299999)
			(layers "B.Cu" "B.Mask" "B.Paste")
			(roundrect_rratio 0.25)
			(net 50 "+3V3")
			(pinfunction "MODE")
			(pintype "input")
		)
		(pad "6" smd roundrect
			(at 0.74 -0.2495 270)
			(size 0.670001 0.299999)
			(layers "B.Cu" "B.Mask" "B.Paste")
			(roundrect_rratio 0.25)
			(net 50 "+3V3")
			(pinfunction "VIN2")
			(pintype "power_in")
		)
		(pad "7" smd roundrect
			(at 0.74 0.2505 270)
			(size 0.670001 0.299999)
			(layers "B.Cu" "B.Mask" "B.Paste")
			(roundrect_rratio 0.25)
			(net 516 "Net-(R50-Pad1)")
			(pinfunction "VOUT")
			(pintype "passive")
		)
		(pad "8" smd roundrect
			(at 0.74 0.7495 270)
			(size 0.670001 0.299999)
			(layers "B.Cu" "B.Mask" "B.Paste")
			(roundrect_rratio 0.25)
			(net 517 "SD_VDD_FLAG")
			(pinfunction "ST")
			(pintype "output")
		)
	)
	(footprint "antmicro-footprints:C_0402_1005Metric"
		(layer "B.Cu")
		(at 223.75 123 90)
		(descr "Capacitor SMD 0402")
		(tags "capacitor SMD 0402")
		(property "Reference" "C18"
			(at 0.95 0.55 270)
			(layer "B.SilkS")
			(effects
				(font
					(size 0.7 0.7)
					(thickness 0.15)
				)
				(justify right bottom mirror)
			)
		)
		(property "Value" "C_100n_0402"
			(at -1.022927 -2.155213 90)
			(layer "B.Fab")
			(hide yes)
			(effects
				(font
					(size 0.7 0.7)
					(thickness 0.15)
				)
				(justify right bottom mirror)
			)
		)
		(property "Datasheet" "https://www.murata.com/products/productdetail?partno=GRM155R61H104KE14%23"
			(at 0 0 90)
			(layer "F.Fab")
			(hide yes)
			(effects
				(font
					(size 1.27 1.27)
					(thickness 0.15)
				)
			)
		)
		(property "Description" "SMD Multilayer Ceramic Capacitor, 0.1 µF, 50 V, 0402 [1005 Metric], ± 10%, X5R, GRM Series"
			(at 0 0 90)
			(layer "F.Fab")
			(hide yes)
			(effects
				(font
					(size 1.27 1.27)
					(thickness 0.15)
				)
			)
		)
		(property "Author" "Antmicro"
			(at 346.75 -100.75 0)
			(layer "B.Fab")
			(hide yes)
			(effects
				(font
					(size 1 1)
					(thickness 0.15)
				)
				(justify mirror)
			)
		)
		(property "Dielectric" "X5R"
			(at 346.75 -100.75 0)
			(layer "B.Fab")
			(hide yes)
			(effects
				(font
					(size 1 1)
					(thickness 0.15)
				)
				(justify mirror)
			)
		)
		(property "License" "Apache-2.0"
			(at 346.75 -100.75 0)
			(layer "B.Fab")
			(hide yes)
			(effects
				(font
					(size 1 1)
					(thickness 0.15)
				)
				(justify mirror)
			)
		)
		(property "MPN" "GRM155R61H104KE14D"
			(at 346.75 -100.75 0)
			(layer "B.Fab")
			(hide yes)
			(effects
				(font
					(size 1 1)
					(thickness 0.15)
				)
				(justify mirror)
			)
		)
		(property "Manufacturer" "Murata"
			(at 346.75 -100.75 0)
			(layer "B.Fab")
			(hide yes)
			(effects
				(font
					(size 1 1)
					(thickness 0.15)
				)
				(justify mirror)
			)
		)
		(property "Public" ""
			(at 346.75 -100.75 0)
			(layer "B.Fab")
			(hide yes)
			(effects
				(font
					(size 1 1)
					(thickness 0.15)
				)
				(justify mirror)
			)
		)
		(property "Val" "100n"
			(at 346.75 -100.75 0)
			(layer "B.Fab")
			(hide yes)
			(effects
				(font
					(size 1 1)
					(thickness 0.15)
				)
				(justify mirror)
			)
		)
		(property "Voltage" "50V"
			(at 346.75 -100.75 0)
			(layer "B.Fab")
			(hide yes)
			(effects
				(font
					(size 1 1)
					(thickness 0.15)
				)
				(justify mirror)
			)
		)
		(sheetname "/FPGA GPIO/")
		(sheetfile "fpga-gpio.kicad_sch")
		(attr smd)
		(fp_rect
			(start -0.925 0.47)
			(end 0.925 -0.47)
			(stroke
				(width 0.05)
				(type default)
			)
			(fill no)
			(layer "B.CrtYd")
		)
		(fp_line
			(start 0.504 -0.248)
			(end -0.494 -0.248)
			(stroke
				(width 0.15)
				(type solid)
			)
			(layer "B.Fab")
		)
		(fp_line
			(start -0.494 -0.248)
			(end -0.494 0.25)
			(stroke
				(width 0.15)
				(type solid)
			)
			(layer "B.Fab")
		)
		(fp_line
			(start 0.504 0.25)
			(end 0.504 -0.248)
			(stroke
				(width 0.15)
				(type solid)
			)
			(layer "B.Fab")
		)
		(fp_line
			(start -0.494 0.25)
			(end 0.504 0.25)
			(stroke
				(width 0.15)
				(type solid)
			)
			(layer "B.Fab")
		)
		(fp_text user "Author: Antmicro"
			(at -0.939 -3.399 270)
			(layer "B.Fab")
			(effects
				(font
					(size 0.7 0.7)
					(thickness 0.15)
				)
				(justify left bottom mirror)
			)
		)
		(fp_text user "License: Apache-2.0"
			(at -0.939 -5.799 270)
			(layer "B.Fab")
			(effects
				(font
					(size 0.7 0.7)
					(thickness 0.15)
				)
				(justify left bottom mirror)
			)
		)
		(fp_text user "${REFERENCE}"
			(at -0.939 -4.599 270)
			(layer "B.Fab")
			(effects
				(font
					(size 0.7 0.7)
					(thickness 0.15)
				)
				(justify left bottom mirror)
			)
		)
		(pad "1" smd roundrect
			(at -0.48 0 90)
			(size 0.59 0.64)
			(layers "B.Cu" "B.Mask" "B.Paste")
			(roundrect_rratio 0.25)
			(net 649 "VDD")
			(pintype "passive")
		)
		(pad "2" smd roundrect
			(at 0.48 0 90)
			(size 0.59 0.64)
			(layers "B.Cu" "B.Mask" "B.Paste")
			(roundrect_rratio 0.25)
			(net 417 "GND")
			(pintype "passive")
		)
	)
)
